# SCM (Grand Teton) — schematic netlist excerpt (pin names and nets, part order shuffled) for the footprints in the layout excerpt that follows; sources: Cadence DE-HDL packaged netlist, KiCad conversion of 12092022_DA0F0TMDCD0_F0T_Management_Board_D_brd_V3_OCP.brd

R162  Q_RES  33.2 1% CHIP  pkg 0402LF  page 12 : A = SMB_BMC_MM15_SCL ; B = SMB_BMC_MM15_R_SCL
R671  Q_RES  0 5% CHIP  pkg 0402LF  page 29 : A = USB3_01_TXP_C ; B = USB3_FPNL_TXP

(kicad_pcb
	(version 20260206)
	(generator "pcbnew")
	(generator_version "10.0")
	(general
		(thickness 1.6)
		(legacy_teardrops no)
	)
	(paper "A4")
	(title_block
		(title "12092022_DA0F0TMDCD0_F0T_Management_Board_D_brd_V3_OCP.brd")
		(comment 1 "Grand Teton / footprints 1345-1346 of 1440")
	)
	(layers
		(0 "F.Cu" signal "TOP")
		(4 "In1.Cu" signal "GND")
		(6 "In2.Cu" signal "IN1")
		(8 "In3.Cu" signal "GND1")
		(10 "In4.Cu" signal "IN2")
		(12 "In5.Cu" signal "VCC")
		(14 "In6.Cu" signal "VCC1")
		(16 "In7.Cu" signal "IN3")
		(18 "In8.Cu" signal "GND2")
		(20 "In9.Cu" signal "IN4")
		(22 "In10.Cu" signal "GND3")
		(2 "B.Cu" signal "BOTTOM")
		(9 "F.Adhes" user "F.Adhesive")
		(11 "B.Adhes" user "B.Adhesive")
		(13 "F.Paste" user "Package Geometry/Pastemask Top")
		(15 "B.Paste" user "Package Geometry/Pastemask Bottom")
		(5 "F.SilkS" user "Ref Des/Silkscreen Top")
		(7 "B.SilkS" user "Ref Des/Silkscreen Bottom")
		(1 "F.Mask" user "Board Geometry/Soldermask Top")
		(3 "B.Mask" user "Board Geometry/Soldermask Bottom")
		(17 "Dwgs.User" user "User.Drawings")
		(19 "Cmts.User" user "User.Comments")
		(21 "Eco1.User" user "User.Eco1")
		(23 "Eco2.User" user "User.Eco2")
		(25 "Edge.Cuts" user "Board Geometry/Outline")
		(27 "Margin" user)
		(31 "F.CrtYd" user "Package Geometry/Place Bound Top")
		(29 "B.CrtYd" user "Package Geometry/Place Bound Bottom")
		(35 "F.Fab" user "Ref Des/Assembly Top")
		(33 "B.Fab" user "Ref Des/Assembly Bottom")
	)
	(footprint ""
		(layer "B.Cu")
		(at 48.514 -34.671 -90)
		(property "Reference" "R162"
			(at 0 0 90)
			(layer "B.SilkS")
			(hide yes)
			(effects
				(font
					(size 1.27 1.27)
				)
				(justify mirror)
			)
		)
		(property "Value" ""
			(at 0 0 90)
			(layer "B.Fab")
			(effects
				(font
					(size 1.27 1.27)
				)
				(justify mirror)
			)
		)
		(duplicate_pad_numbers_are_jumpers no)
		(fp_line
			(start -0.7874 0.4064)
			(end 0.7874 0.4064)
			(stroke
				(width 0.1524)
				(type default)
			)
			(layer "B.SilkS")
		)
		(fp_line
			(start 0.7874 0.4064)
			(end 0.7874 -0.4064)
			(stroke
				(width 0.1524)
				(type default)
			)
			(layer "B.SilkS")
		)
		(fp_line
			(start -0.7874 -0.4064)
			(end -0.7874 0.4064)
			(stroke
				(width 0.1524)
				(type default)
			)
			(layer "B.SilkS")
		)
		(fp_line
			(start 0.7874 -0.4064)
			(end -0.7874 -0.4064)
			(stroke
				(width 0.1524)
				(type default)
			)
			(layer "B.SilkS")
		)
		(fp_line
			(start -0.67945 0.3048)
			(end -0.120396 0.3048)
			(stroke
				(width 0.1)
				(type default)
			)
			(layer "B.Fab")
		)
		(fp_line
			(start -0.120396 0.3048)
			(end -0.120396 0.2794)
			(stroke
				(width 0.1)
				(type default)
			)
			(layer "B.Fab")
		)
		(fp_line
			(start 0.12065 0.3048)
			(end 0.67945 0.3048)
			(stroke
				(width 0.1)
				(type default)
			)
			(layer "B.Fab")
		)
		(fp_line
			(start 0.67945 0.3048)
			(end 0.67945 -0.305054)
			(stroke
				(width 0.1)
				(type default)
			)
			(layer "B.Fab")
		)
		(fp_line
			(start -0.120396 0.2794)
			(end 0.12065 0.2794)
			(stroke
				(width 0.1)
				(type default)
			)
			(layer "B.Fab")
		)
		(fp_line
			(start 0.12065 0.2794)
			(end 0.12065 0.3048)
			(stroke
				(width 0.1)
				(type default)
			)
			(layer "B.Fab")
		)
		(fp_line
			(start -0.12065 -0.2794)
			(end -0.12065 -0.3048)
			(stroke
				(width 0.1)
				(type default)
			)
			(layer "B.Fab")
		)
		(fp_line
			(start 0.12065 -0.2794)
			(end -0.12065 -0.2794)
			(stroke
				(width 0.1)
				(type default)
			)
			(layer "B.Fab")
		)
		(fp_line
			(start -0.67945 -0.3048)
			(end -0.67945 0.3048)
			(stroke
				(width 0.1)
				(type default)
			)
			(layer "B.Fab")
		)
		(fp_line
			(start -0.12065 -0.3048)
			(end -0.67945 -0.3048)
			(stroke
				(width 0.1)
				(type default)
			)
			(layer "B.Fab")
		)
		(fp_line
			(start 0.12065 -0.305054)
			(end 0.12065 -0.2794)
			(stroke
				(width 0.1)
				(type default)
			)
			(layer "B.Fab")
		)
		(fp_line
			(start 0.67945 -0.305054)
			(end 0.12065 -0.305054)
			(stroke
				(width 0.1)
				(type default)
			)
			(layer "B.Fab")
		)
		(pad "1" smd circle
			(at 0.40005 0 90)
			(size 0 0)
			(layers "B.Cu" "B.Mask" "B.Paste")
			(net "SMB_BMC_MM15_SCL")
		)
		(pad "2" smd circle
			(at -0.40005 0 90)
			(size 0 0)
			(layers "B.Cu" "B.Mask" "B.Paste")
			(net "SMB_BMC_MM15_R_SCL")
		)
	)
	(footprint ""
		(layer "B.Cu")
		(at 46.355 -96.8248 -90)
		(property "Reference" "R671"
			(at 0 0 90)
			(layer "B.SilkS")
			(hide yes)
			(effects
				(font
					(size 1.27 1.27)
				)
				(justify mirror)
			)
		)
		(property "Value" ""
			(at 0 0 90)
			(layer "B.Fab")
			(effects
				(font
					(size 1.27 1.27)
				)
				(justify mirror)
			)
		)
		(duplicate_pad_numbers_are_jumpers no)
		(fp_line
			(start -0.7874 0.4064)
			(end 0.7874 0.4064)
			(stroke
				(width 0.1524)
				(type default)
			)
			(layer "B.SilkS")
		)
		(fp_line
			(start 0.7874 0.4064)
			(end 0.7874 -0.4064)
			(stroke
				(width 0.1524)
				(type default)
			)
			(layer "B.SilkS")
		)
		(fp_line
			(start -0.7874 -0.4064)
			(end -0.7874 0.4064)
			(stroke
				(width 0.1524)
				(type default)
			)
			(layer "B.SilkS")
		)
		(fp_line
			(start 0.7874 -0.4064)
			(end -0.7874 -0.4064)
			(stroke
				(width 0.1524)
				(type default)
			)
			(layer "B.SilkS")
		)
		(fp_line
			(start -0.67945 0.3048)
			(end -0.120396 0.3048)
			(stroke
				(width 0.1)
				(type default)
			)
			(layer "B.Fab")
		)
		(fp_line
			(start -0.120396 0.3048)
			(end -0.120396 0.2794)
			(stroke
				(width 0.1)
				(type default)
			)
			(layer "B.Fab")
		)
		(fp_line
			(start 0.12065 0.3048)
			(end 0.67945 0.3048)
			(stroke
				(width 0.1)
				(type default)
			)
			(layer "B.Fab")
		)
		(fp_line
			(start 0.67945 0.3048)
			(end 0.67945 -0.305054)
			(stroke
				(width 0.1)
				(type default)
			)
			(layer "B.Fab")
		)
		(fp_line
			(start -0.120396 0.2794)
			(end 0.12065 0.2794)
			(stroke
				(width 0.1)
				(type default)
			)
			(layer "B.Fab")
		)
		(fp_line
			(start 0.12065 0.2794)
			(end 0.12065 0.3048)
			(stroke
				(width 0.1)
				(type default)
			)
			(layer "B.Fab")
		)
		(fp_line
			(start -0.12065 -0.2794)
			(end -0.12065 -0.3048)
			(stroke
				(width 0.1)
				(type default)
			)
			(layer "B.Fab")
		)
		(fp_line
			(start 0.12065 -0.2794)
			(end -0.12065 -0.2794)
			(stroke
				(width 0.1)
				(type default)
			)
			(layer "B.Fab")
		)
		(fp_line
			(start -0.67945 -0.3048)
			(end -0.67945 0.3048)
			(stroke
				(width 0.1)
				(type default)
			)
			(layer "B.Fab")
		)
		(fp_line
			(start -0.12065 -0.3048)
			(end -0.67945 -0.3048)
			(stroke
				(width 0.1)
				(type default)
			)
			(layer "B.Fab")
		)
		(fp_line
			(start 0.12065 -0.305054)
			(end 0.12065 -0.2794)
			(stroke
				(width 0.1)
				(type default)
			)
			(layer "B.Fab")
		)
		(fp_line
			(start 0.67945 -0.305054)
			(end 0.12065 -0.305054)
			(stroke
				(width 0.1)
				(type default)
			)
			(layer "B.Fab")
		)
		(pad "1" smd circle
			(at 0.40005 0 90)
			(size 0 0)
			(layers "B.Cu" "B.Mask" "B.Paste")
			(net "USB3_01_TXP_C")
		)
		(pad "2" smd circle
			(at -0.40005 0 90)
			(size 0 0)
			(layers "B.Cu" "B.Mask" "B.Paste")
			(net "USB3_FPNL_TXP")
		)
	)
)
